# T6G (Grand Teton) — schematic netlist excerpt (pin names and nets, part order shuffled) for the footprints in the layout excerpt that follows; sources: Cadence DE-HDL packaged netlist, KiCad conversion of 04192023_DAF0TMB3IC0_F0TG_MB_C_brd_V02_OCP.brd

H112  GND_HOLE  EMPTY  pkg TH  page 230
  GND2  = GND
  GND3  = GND
  GND4  = GND
  GND5  = GND
  GND6  = GND
  GND7  = GND
  GND8  = GND
  GND9  = GND

(kicad_pcb
	(version 20260206)
	(generator "pcbnew")
	(generator_version "10.0")
	(general
		(thickness 1.6)
		(legacy_teardrops no)
	)
	(paper "A4")
	(title_block
		(title "04192023_DAF0TMB3IC0_F0TG_MB_C_brd_V02_OCP.brd")
		(comment 1 "Grand Teton / footprints 781-781 of 8354")
	)
	(layers
		(0 "F.Cu" signal "TOP")
		(4 "In1.Cu" signal "GND")
		(6 "In2.Cu" signal "IN1")
		(8 "In3.Cu" signal "GND1")
		(10 "In4.Cu" signal "IN2")
		(12 "In5.Cu" signal "GND2")
		(14 "In6.Cu" signal "IN3")
		(16 "In7.Cu" signal "GND3")
		(18 "In8.Cu" signal "VCC")
		(20 "In9.Cu" signal "VCC1")
		(22 "In10.Cu" signal "GND4")
		(24 "In11.Cu" signal "IN4")
		(26 "In12.Cu" signal "GND5")
		(28 "In13.Cu" signal "IN5")
		(30 "In14.Cu" signal "GND6")
		(32 "In15.Cu" signal "IN6")
		(34 "In16.Cu" signal "GND7")
		(2 "B.Cu" signal "BOTTOM")
		(9 "F.Adhes" user "F.Adhesive")
		(11 "B.Adhes" user "B.Adhesive")
		(13 "F.Paste" user "Package Geometry/Pastemask Top")
		(15 "B.Paste" user "Package Geometry/Pastemask Bottom")
		(5 "F.SilkS" user "Ref Des/Silkscreen Top")
		(7 "B.SilkS" user "Ref Des/Silkscreen Bottom")
		(1 "F.Mask" user "Board Geometry/Soldermask Top")
		(3 "B.Mask" user "Board Geometry/Soldermask Bottom")
		(17 "Dwgs.User" user "User.Drawings")
		(19 "Cmts.User" user "User.Comments")
		(21 "Eco1.User" user "User.Eco1")
		(23 "Eco2.User" user "User.Eco2")
		(25 "Edge.Cuts" user "Board Geometry/Outline")
		(27 "Margin" user)
		(31 "F.CrtYd" user "Package Geometry/Place Bound Top")
		(29 "B.CrtYd" user "Package Geometry/Place Bound Bottom")
		(35 "F.Fab" user "Ref Des/Assembly Top")
		(33 "B.Fab" user "Ref Des/Assembly Bottom")
	)
	(footprint ""
		(layer "F.Cu")
		(at 258.12496 -360.764074)
		(property "Reference" "H112"
			(at -4.58216 -9.007856 0)
			(unlocked yes)
			(layer "F.SilkS")
			(effects
				(font
					(size 0.7874 0.5842)
					(thickness 0.1524)
				)
				(justify left)
			)
		)
		(property "Value" ""
			(at 0 0 0)
			(layer "F.Fab")
			(effects
				(font
					(size 1.27 1.27)
				)
			)
		)
		(duplicate_pad_numbers_are_jumpers no)
		(fp_circle
			(center 0 0)
			(end 7.999984 0)
			(stroke
				(width 0.1524)
				(type default)
			)
			(fill no)
			(layer "F.SilkS")
		)
		(fp_circle
			(center 0 0)
			(end 7.999984 0)
			(stroke
				(width 0.1524)
				(type default)
			)
			(fill no)
			(layer "B.SilkS")
		)
		(fp_circle
			(center 0 0)
			(end 7.999984 0)
			(stroke
				(width 0.1)
				(type default)
			)
			(fill no)
			(layer "B.Fab")
		)
		(fp_circle
			(center 0 0)
			(end 7.999984 0)
			(stroke
				(width 0.1)
				(type default)
			)
			(fill no)
			(layer "F.Fab")
		)
		(pad "" np_thru_hole circle
			(at 0 0)
			(size 4.0132 4.0132)
			(drill 4.0132)
			(layers "*.Cu" "*.Mask")
			(clearance 0.381)
			(thermal_gap 0.381)
		)
		(pad "2" thru_hole circle
			(at 3.2639 0)
			(size 0.9144 0.9144)
			(drill 0.5588)
			(layers "*.Cu" "*.Mask")
			(remove_unused_layers no)
			(net "GND")
			(clearance 0.0762)
			(thermal_gap 0.0762)
		)
		(pad "3" thru_hole circle
			(at 2.307844 -2.307844)
			(size 0.9144 0.9144)
			(drill 0.5588)
			(layers "*.Cu" "*.Mask")
			(remove_unused_layers no)
			(net "GND")
			(clearance 0.0762)
			(thermal_gap 0.0762)
		)
		(pad "4" thru_hole circle
			(at 0 -3.2639)
			(size 0.9144 0.9144)
			(drill 0.5588)
			(layers "*.Cu" "*.Mask")
			(remove_unused_layers no)
			(net "GND")
			(clearance 0.0762)
			(thermal_gap 0.0762)
		)
		(pad "5" thru_hole circle
			(at -2.307844 -2.307844)
			(size 0.9144 0.9144)
			(drill 0.5588)
			(layers "*.Cu" "*.Mask")
			(remove_unused_layers no)
			(net "GND")
			(clearance 0.0762)
			(thermal_gap 0.0762)
		)
		(pad "6" thru_hole circle
			(at -3.2639 0)
			(size 0.9144 0.9144)
			(drill 0.5588)
			(layers "*.Cu" "*.Mask")
			(remove_unused_layers no)
			(net "GND")
			(clearance 0.0762)
			(thermal_gap 0.0762)
		)
		(pad "7" thru_hole circle
			(at -2.307844 2.307844)
			(size 0.9144 0.9144)
			(drill 0.5588)
			(layers "*.Cu" "*.Mask")
			(remove_unused_layers no)
			(net "GND")
			(clearance 0.0762)
			(thermal_gap 0.0762)
		)
		(pad "8" thru_hole circle
			(at 0 3.2639)
			(size 0.9144 0.9144)
			(drill 0.5588)
			(layers "*.Cu" "*.Mask")
			(remove_unused_layers no)
			(net "GND")
			(clearance 0.0762)
			(thermal_gap 0.0762)
		)
		(pad "9" thru_hole circle
			(at 2.307844 2.307844)
			(size 0.9144 0.9144)
			(drill 0.5588)
			(layers "*.Cu" "*.Mask")
			(remove_unused_layers no)
			(net "GND")
			(clearance 0.0762)
			(thermal_gap 0.0762)
		)
		(zone
			(layer "F.Cu")
			(hatch none 0.5)
			(connect_pads
				(clearance 0)
			)
			(min_thickness 0.25)
			(keepout
				(tracks not_allowed)
				(vias allowed)
				(pads allowed)
				(copperpour not_allowed)
				(footprints allowed)
			)
			(placement
				(enabled no)
				(sheetname "")
			)
			(fill
				(thermal_gap 0.5)
				(thermal_bridge_width 0.5)
				(island_removal_mode 0)
			)
			(polygon
				(pts
					(arc
						(start 258.12496 -356.496874)
						(mid 253.85776 -360.764074)
						(end 258.12496 -365.031274)
					)
					(arc
						(start 258.12496 -368.764058)
						(mid 252.468117 -366.420917)
						(end 250.124976 -360.764074)
					)
					(arc
						(start 250.124976 -360.764074)
						(mid 252.468117 -355.107231)
						(end 258.12496 -352.76409)
					)
				)
			)
		)
		(zone
			(layer "F.Cu")
			(hatch none 0.5)
			(connect_pads
				(clearance 0)
			)
			(min_thickness 0.25)
			(keepout
				(tracks not_allowed)
				(vias allowed)
				(pads allowed)
				(copperpour not_allowed)
				(footprints allowed)
			)
			(placement
				(enabled no)
				(sheetname "")
			)
			(fill
				(thermal_gap 0.5)
				(thermal_bridge_width 0.5)
				(island_removal_mode 0)
			)
			(polygon
				(pts
					(arc
						(start 258.12496 -356.496874)
						(mid 262.39216 -360.764074)
						(end 258.12496 -365.031274)
					)
					(arc
						(start 258.12496 -368.764058)
						(mid 263.781803 -366.420917)
						(end 266.124944 -360.764074)
					)
					(arc
						(start 266.124944 -360.764074)
						(mid 263.781803 -355.107231)
						(end 258.12496 -352.76409)
					)
				)
			)
		)
		(zone
			(layers "F.Cu" "B.Cu" "In1.Cu" "In2.Cu" "In3.Cu" "In4.Cu" "In5.Cu" "In6.Cu"
				"In7.Cu" "In8.Cu" "In9.Cu" "In10.Cu" "In11.Cu" "In12.Cu" "In13.Cu" "In14.Cu"
				"In15.Cu" "In16.Cu"
			)
			(hatch none 0.5)
			(connect_pads
				(clearance 0)
			)
			(min_thickness 0.25)
			(keepout
				(tracks not_allowed)
				(vias allowed)
				(pads allowed)
				(copperpour not_allowed)
				(footprints allowed)
			)
			(placement
				(enabled no)
				(sheetname "")
			)
			(fill
				(thermal_gap 0.5)
				(thermal_bridge_width 0.5)
				(island_removal_mode 0)
			)
			(polygon
				(pts
					(arc
						(start 260.63702 -360.764074)
						(mid 255.6129 -360.764074)
						(end 260.63702 -360.764074)
					)
				)
			)
		)
	)
)
